# T6G (Grand Teton) — schematic netlist excerpt (pin names and nets, part order shuffled) for the footprints in the layout excerpt that follows; sources: Cadence DE-HDL packaged netlist, KiCad conversion of 04192023_DAF0TMB3IC0_F0TG_MB_C_brd_V02_OCP.brd

R3194  Q_RES  0 5% CHIP  pkg 0402LF  page 55 : A = CLK_100M_CPU1_CLK02_R_DP ; B = CLK_100M_CPU1_CLK02_DP
R4559  Q_RES  100K 1% CHIP  pkg 0402LF  page 125 : A = SWB_HSC_PWRGD ; B = GND

(kicad_pcb
	(version 20260206)
	(generator "pcbnew")
	(generator_version "10.0")
	(general
		(thickness 1.6)
		(legacy_teardrops no)
	)
	(paper "A4")
	(title_block
		(title "04192023_DAF0TMB3IC0_F0TG_MB_C_brd_V02_OCP.brd")
		(comment 1 "Grand Teton / footprints 3486-3487 of 8354")
	)
	(layers
		(0 "F.Cu" signal "TOP")
		(4 "In1.Cu" signal "GND")
		(6 "In2.Cu" signal "IN1")
		(8 "In3.Cu" signal "GND1")
		(10 "In4.Cu" signal "IN2")
		(12 "In5.Cu" signal "GND2")
		(14 "In6.Cu" signal "IN3")
		(16 "In7.Cu" signal "GND3")
		(18 "In8.Cu" signal "VCC")
		(20 "In9.Cu" signal "VCC1")
		(22 "In10.Cu" signal "GND4")
		(24 "In11.Cu" signal "IN4")
		(26 "In12.Cu" signal "GND5")
		(28 "In13.Cu" signal "IN5")
		(30 "In14.Cu" signal "GND6")
		(32 "In15.Cu" signal "IN6")
		(34 "In16.Cu" signal "GND7")
		(2 "B.Cu" signal "BOTTOM")
		(9 "F.Adhes" user "F.Adhesive")
		(11 "B.Adhes" user "B.Adhesive")
		(13 "F.Paste" user "Package Geometry/Pastemask Top")
		(15 "B.Paste" user "Package Geometry/Pastemask Bottom")
		(5 "F.SilkS" user "Ref Des/Silkscreen Top")
		(7 "B.SilkS" user "Ref Des/Silkscreen Bottom")
		(1 "F.Mask" user "Board Geometry/Soldermask Top")
		(3 "B.Mask" user "Board Geometry/Soldermask Bottom")
		(17 "Dwgs.User" user "User.Drawings")
		(19 "Cmts.User" user "User.Comments")
		(21 "Eco1.User" user "User.Eco1")
		(23 "Eco2.User" user "User.Eco2")
		(25 "Edge.Cuts" user "Board Geometry/Outline")
		(27 "Margin" user)
		(31 "F.CrtYd" user "Package Geometry/Place Bound Top")
		(29 "B.CrtYd" user "Package Geometry/Place Bound Bottom")
		(35 "F.Fab" user "Ref Des/Assembly Top")
		(33 "B.Fab" user "Ref Des/Assembly Bottom")
	)
	(footprint ""
		(layer "F.Cu")
		(at 155.306522 -191.361314 -90)
		(property "Reference" "R3194"
			(at 0 0 270)
			(layer "F.SilkS")
			(hide yes)
			(effects
				(font
					(size 1.27 1.27)
				)
			)
		)
		(property "Value" ""
			(at 0 0 270)
			(layer "F.Fab")
			(effects
				(font
					(size 1.27 1.27)
				)
			)
		)
		(duplicate_pad_numbers_are_jumpers no)
		(fp_line
			(start -0.7874 0.4064)
			(end -0.7874 -0.039878)
			(stroke
				(width 0.1524)
				(type default)
			)
			(layer "F.SilkS")
		)
		(fp_line
			(start 0.7874 0.4064)
			(end -0.7874 0.4064)
			(stroke
				(width 0.1524)
				(type default)
			)
			(layer "F.SilkS")
		)
		(fp_line
			(start 0.7874 -0.065278)
			(end 0.7874 0.4064)
			(stroke
				(width 0.1524)
				(type default)
			)
			(layer "F.SilkS")
		)
		(fp_line
			(start -0.383286 -0.4064)
			(end 0.353314 -0.4064)
			(stroke
				(width 0.1524)
				(type default)
			)
			(layer "F.SilkS")
		)
		(fp_line
			(start -0.67945 0.3048)
			(end -0.67945 -0.305054)
			(stroke
				(width 0.1)
				(type default)
			)
			(layer "F.Fab")
		)
		(fp_line
			(start -0.12065 0.3048)
			(end -0.67945 0.3048)
			(stroke
				(width 0.1)
				(type default)
			)
			(layer "F.Fab")
		)
		(fp_line
			(start 0.120396 0.3048)
			(end 0.120396 0.2794)
			(stroke
				(width 0.1)
				(type default)
			)
			(layer "F.Fab")
		)
		(fp_line
			(start 0.67945 0.3048)
			(end 0.120396 0.3048)
			(stroke
				(width 0.1)
				(type default)
			)
			(layer "F.Fab")
		)
		(fp_line
			(start -0.12065 0.2794)
			(end -0.12065 0.3048)
			(stroke
				(width 0.1)
				(type default)
			)
			(layer "F.Fab")
		)
		(fp_line
			(start 0.120396 0.2794)
			(end -0.12065 0.2794)
			(stroke
				(width 0.1)
				(type default)
			)
			(layer "F.Fab")
		)
		(fp_line
			(start -0.12065 -0.2794)
			(end 0.12065 -0.2794)
			(stroke
				(width 0.1)
				(type default)
			)
			(layer "F.Fab")
		)
		(fp_line
			(start 0.12065 -0.2794)
			(end 0.12065 -0.3048)
			(stroke
				(width 0.1)
				(type default)
			)
			(layer "F.Fab")
		)
		(fp_line
			(start 0.12065 -0.3048)
			(end 0.67945 -0.3048)
			(stroke
				(width 0.1)
				(type default)
			)
			(layer "F.Fab")
		)
		(fp_line
			(start 0.67945 -0.3048)
			(end 0.67945 0.3048)
			(stroke
				(width 0.1)
				(type default)
			)
			(layer "F.Fab")
		)
		(fp_line
			(start -0.67945 -0.305054)
			(end -0.12065 -0.305054)
			(stroke
				(width 0.1)
				(type default)
			)
			(layer "F.Fab")
		)
		(fp_line
			(start -0.12065 -0.305054)
			(end -0.12065 -0.2794)
			(stroke
				(width 0.1)
				(type default)
			)
			(layer "F.Fab")
		)
		(pad "1" smd circle
			(at -0.40005 0 270)
			(size 0 0)
			(layers "F.Cu" "F.Mask" "F.Paste")
			(net "CLK_100M_CPU1_CLK02_R_DP")
		)
		(pad "2" smd circle
			(at 0.40005 0 270)
			(size 0 0)
			(layers "F.Cu" "F.Mask" "F.Paste")
			(net "CLK_100M_CPU1_CLK02_DP")
		)
	)
	(footprint ""
		(layer "F.Cu")
		(at 351.407222 -424.279314 180)
		(property "Reference" "R4559"
			(at 0 0 180)
			(layer "F.SilkS")
			(hide yes)
			(effects
				(font
					(size 1.27 1.27)
				)
			)
		)
		(property "Value" ""
			(at 0 0 180)
			(layer "F.Fab")
			(effects
				(font
					(size 1.27 1.27)
				)
			)
		)
		(duplicate_pad_numbers_are_jumpers no)
		(fp_line
			(start 0.7874 0.4064)
			(end -0.7874 0.4064)
			(stroke
				(width 0.1524)
				(type default)
			)
			(layer "F.SilkS")
		)
		(fp_line
			(start 0.7874 -0.4064)
			(end 0.7874 0.4064)
			(stroke
				(width 0.1524)
				(type default)
			)
			(layer "F.SilkS")
		)
		(fp_line
			(start -0.7874 0.4064)
			(end -0.7874 -0.4064)
			(stroke
				(width 0.1524)
				(type default)
			)
			(layer "F.SilkS")
		)
		(fp_line
			(start -0.7874 -0.4064)
			(end 0.7874 -0.4064)
			(stroke
				(width 0.1524)
				(type default)
			)
			(layer "F.SilkS")
		)
		(fp_line
			(start 0.67945 0.3048)
			(end 0.120396 0.3048)
			(stroke
				(width 0.1)
				(type default)
			)
			(layer "F.Fab")
		)
		(fp_line
			(start 0.67945 -0.3048)
			(end 0.67945 0.3048)
			(stroke
				(width 0.1)
				(type default)
			)
			(layer "F.Fab")
		)
		(fp_line
			(start 0.12065 -0.2794)
			(end 0.12065 -0.3048)
			(stroke
				(width 0.1)
				(type default)
			)
			(layer "F.Fab")
		)
		(fp_line
			(start 0.12065 -0.3048)
			(end 0.67945 -0.3048)
			(stroke
				(width 0.1)
				(type default)
			)
			(layer "F.Fab")
		)
		(fp_line
			(start 0.120396 0.3048)
			(end 0.120396 0.2794)
			(stroke
				(width 0.1)
				(type default)
			)
			(layer "F.Fab")
		)
		(fp_line
			(start 0.120396 0.2794)
			(end -0.12065 0.2794)
			(stroke
				(width 0.1)
				(type default)
			)
			(layer "F.Fab")
		)
		(fp_line
			(start -0.12065 0.3048)
			(end -0.67945 0.3048)
			(stroke
				(width 0.1)
				(type default)
			)
			(layer "F.Fab")
		)
		(fp_line
			(start -0.12065 0.2794)
			(end -0.12065 0.3048)
			(stroke
				(width 0.1)
				(type default)
			)
			(layer "F.Fab")
		)
		(fp_line
			(start -0.12065 -0.2794)
			(end 0.12065 -0.2794)
			(stroke
				(width 0.1)
				(type default)
			)
			(layer "F.Fab")
		)
		(fp_line
			(start -0.12065 -0.305054)
			(end -0.12065 -0.2794)
			(stroke
				(width 0.1)
				(type default)
			)
			(layer "F.Fab")
		)
		(fp_line
			(start -0.67945 0.3048)
			(end -0.67945 -0.305054)
			(stroke
				(width 0.1)
				(type default)
			)
			(layer "F.Fab")
		)
		(fp_line
			(start -0.67945 -0.305054)
			(end -0.12065 -0.305054)
			(stroke
				(width 0.1)
				(type default)
			)
			(layer "F.Fab")
		)
		(pad "1" smd circle
			(at -0.40005 0 180)
			(size 0 0)
			(layers "F.Cu" "F.Mask" "F.Paste")
			(net "SWB_HSC_PWRGD")
		)
		(pad "2" smd circle
			(at 0.40005 0 180)
			(size 0 0)
			(layers "F.Cu" "F.Mask" "F.Paste")
			(net "GND")
		)
	)
)
